(kicad_pcb
	(version 20241229)
	(generator "pcbnew")
	(generator_version "9.0")
	(general
		(thickness 1.711)
		(legacy_teardrops no)
	)
	(paper "A4")
	(title_block
		(title "Antmicro Baseboard for Jetson AGX Thor")
		(date "2026-02-18")
		(rev "1.1.0")
		(company "Antmicro Ltd")
		(comment 1 "www.antmicro.com")
		(comment 9 "footprints 538-540 of 1170")
	)
	(layers
		(0 "F.Cu" signal)
		(4 "In1.Cu" signal)
		(6 "In2.Cu" signal)
		(8 "In3.Cu" signal)
		(10 "In4.Cu" jumper)
		(12 "In5.Cu" signal)
		(14 "In6.Cu" signal)
		(16 "In7.Cu" signal)
		(18 "In8.Cu" signal)
		(2 "B.Cu" signal)
		(9 "F.Adhes" user "F.Adhesive")
		(11 "B.Adhes" user "B.Adhesive")
		(13 "F.Paste" user)
		(15 "B.Paste" user)
		(5 "F.SilkS" user "F.Silkscreen")
		(7 "B.SilkS" user "B.Silkscreen")
		(1 "F.Mask" user)
		(3 "B.Mask" user)
		(17 "Dwgs.User" user "User.Drawings")
		(19 "Cmts.User" user "User.Comments")
		(21 "Eco1.User" user "User.Eco1")
		(23 "Eco2.User" user "User.Eco2")
		(25 "Edge.Cuts" user)
		(27 "Margin" user)
		(31 "F.CrtYd" user "F.Courtyard")
		(29 "B.CrtYd" user "B.Courtyard")
		(35 "F.Fab" user)
		(33 "B.Fab" user)
	)
	(footprint "antmicro-footprints:Conn_Amphenol_SFP28_Cage_U773GC16382071"
		(locked yes)
		(layer "F.Cu")
		(at 201.826 144.9 90)
		(property "Reference" "J19"
			(at 7.4 -14.826 180)
			(layer "F.SilkS")
			(effects
				(font
					(size 0.7 0.7)
					(thickness 0.15)
				)
				(justify left bottom)
			)
		)
		(property "Value" "Amphenol_SFP28_Cage_U773GC16382071"
			(at -2.012 44.2 90)
			(layer "F.Fab")
			(effects
				(font
					(size 0.7 0.7)
					(thickness 0.15)
				)
				(justify left bottom)
			)
		)
		(property "Datasheet" "https://cdn.amphenol-cs.com/media/wysiwyg/files/documentation/datasheet/inputoutput/hsio_cn_ultraport_sfp.pdf"
			(at -2 49 90)
			(layer "F.Fab")
			(effects
				(font
					(size 0.7 0.7)
					(thickness 0.15)
				)
				(justify left bottom)
			)
		)
		(property "Description" "SFP28 Receptacle Cage"
			(at 7.123 30.001 90)
			(layer "F.Fab")
			(effects
				(font
					(size 0.7 0.7)
					(thickness 0.15)
				)
				(justify left bottom)
			)
		)
		(property "MPN" "U773GC16382071"
			(at 0 0 90)
			(unlocked yes)
			(layer "F.Fab")
			(hide yes)
			(effects
				(font
					(size 1 1)
					(thickness 0.15)
				)
			)
		)
		(property "Manufacturer" "Amphenol"
			(at 0 0 90)
			(unlocked yes)
			(layer "F.Fab")
			(hide yes)
			(effects
				(font
					(size 1 1)
					(thickness 0.15)
				)
			)
		)
		(property "Author" "Antmicro"
			(at 0 0 90)
			(unlocked yes)
			(layer "F.Fab")
			(hide yes)
			(effects
				(font
					(size 1 1)
					(thickness 0.15)
				)
			)
		)
		(property "License" "Apache-2.0"
			(at 0 0 90)
			(unlocked yes)
			(layer "F.Fab")
			(hide yes)
			(effects
				(font
					(size 1 1)
					(thickness 0.15)
				)
			)
		)
		(sheetname "/SFP/")
		(sheetfile "sfp.kicad_sch")
		(attr through_hole)
		(fp_poly
			(pts
				(xy -6.027 11.901) (xy 6.023 11.901) (xy 6.023 13.901) (xy -6.027 13.901)
			)
			(stroke
				(width 0.01)
				(type solid)
			)
			(fill yes)
			(layer "F.Mask")
		)
		(fp_line
			(start 8.128 -12.749)
			(end 6.98 -12.749)
			(stroke
				(width 0.15)
				(type solid)
			)
			(layer "F.SilkS")
		)
		(fp_line
			(start 8.128 -12.749)
			(end 8.128 -11.695)
			(stroke
				(width 0.15)
				(type solid)
			)
			(layer "F.SilkS")
		)
		(fp_line
			(start -8.132 -12.749)
			(end -7.02 -12.749)
			(stroke
				(width 0.15)
				(type solid)
			)
			(layer "F.SilkS")
		)
		(fp_line
			(start -8.132 -12.749)
			(end -8.132 -11.695)
			(stroke
				(width 0.15)
				(type solid)
			)
			(layer "F.SilkS")
		)
		(fp_line
			(start 8.128 35.401)
			(end 8.128 34.305)
			(stroke
				(width 0.15)
				(type solid)
			)
			(layer "F.SilkS")
		)
		(fp_line
			(start 8.128 35.401)
			(end 6.98 35.401)
			(stroke
				(width 0.15)
				(type solid)
			)
			(layer "F.SilkS")
		)
		(fp_line
			(start -8.132 35.401)
			(end -8.132 34.305)
			(stroke
				(width 0.15)
				(type solid)
			)
			(layer "F.SilkS")
		)
		(fp_line
			(start -8.132 35.401)
			(end -7.02 35.401)
			(stroke
				(width 0.15)
				(type solid)
			)
			(layer "F.SilkS")
		)
		(fp_rect
			(start -8.445 -7.2)
			(end 8.425 43.4)
			(stroke
				(width 0.05)
				(type solid)
			)
			(fill no)
			(layer "F.CrtYd")
		)
		(fp_text user "Author: Antmicro"
			(at -2.012 47.8 90)
			(layer "F.Fab")
			(effects
				(font
					(size 0.7 0.7)
					(thickness 0.15)
				)
				(justify left bottom)
			)
		)
		(fp_text user "${REFERENCE}"
			(at -2.012 46.6 90)
			(layer "F.Fab")
			(effects
				(font
					(size 0.7 0.7)
					(thickness 0.15)
				)
				(justify left bottom)
			)
		)
		(fp_text user "License: Apache-2.0"
			(at -2.012 45.4 90)
			(layer "F.Fab")
			(effects
				(font
					(size 0.7 0.7)
					(thickness 0.15)
				)
				(justify left bottom)
			)
		)
		(pad "" np_thru_hole circle
			(at -7.125 -1.6 90)
			(size 0.95 0.95)
			(drill 0.95)
			(layers "*.Cu" "*.Mask")
		)
		(pad "" np_thru_hole circle
			(at -7.125 3.4 90)
			(size 0.95 0.95)
			(drill 0.95)
			(layers "*.Cu" "*.Mask")
		)
		(pad "" np_thru_hole circle
			(at -7.125 8.1 90)
			(size 0.95 0.95)
			(drill 0.95)
			(layers "*.Cu" "*.Mask")
		)
		(pad "" np_thru_hole circle
			(at -4.8 -6.2 90)
			(size 0.95 0.95)
			(drill 0.95)
			(layers "*.Cu" "*.Mask")
		)
		(pad "" np_thru_hole circle
			(at 0 -6.2 90)
			(size 0.95 0.95)
			(drill 0.95)
			(layers "*.Cu" "*.Mask")
		)
		(pad "" np_thru_hole circle
			(at 4.8 -6.2 90)
			(size 0.95 0.95)
			(drill 0.95)
			(layers "*.Cu" "*.Mask")
		)
		(pad "" np_thru_hole circle
			(at 7.125 -1.6 90)
			(size 0.95 0.95)
			(drill 0.95)
			(layers "*.Cu" "*.Mask")
		)
		(pad "" np_thru_hole circle
			(at 7.125 3.4 90)
			(size 0.95 0.95)
			(drill 0.95)
			(layers "*.Cu" "*.Mask")
		)
		(pad "" np_thru_hole circle
			(at 7.125 8.1 90)
			(size 0.95 0.95)
			(drill 0.95)
			(layers "*.Cu" "*.Mask")
		)
		(pad "SH" thru_hole rect
			(at -7.125 0.9 90)
			(size 2 2)
			(drill 0.85)
			(layers "*.Cu" "*.Mask")
			(remove_unused_layers no)
			(net 379 "/SFP/SH")
			(pinfunction "SH")
			(pintype "passive")
			(solder_mask_margin 0.102)
		)
		(pad "SH" thru_hole rect
			(at -7.125 10.9 90)
			(size 2 2)
			(drill 1.1)
			(layers "*.Cu" "*.Mask")
			(remove_unused_layers no)
			(net 379 "/SFP/SH")
			(pinfunction "SH")
			(pintype "passive")
			(solder_mask_margin 0.102)
		)
		(pad "SH" thru_hole rect
			(at -7.125 20.9 90)
			(size 2 2)
			(drill 1.1)
			(layers "*.Cu" "*.Mask")
			(remove_unused_layers no)
			(net 379 "/SFP/SH")
			(pinfunction "SH")
			(pintype "passive")
			(solder_mask_margin 0.102)
		)
		(pad "SH" thru_hole rect
			(at -7.125 30.9 90)
			(size 2 2)
			(drill 1.1)
			(layers "*.Cu" "*.Mask")
			(remove_unused_layers no)
			(net 379 "/SFP/SH")
			(pinfunction "SH")
			(pintype "passive")
			(solder_mask_margin 0.102)
		)
		(pad "SH" smd rect
			(at 0 12.9 90)
			(size 12.05 2)
			(layers "F.Cu" "F.Paste")
			(net 379 "/SFP/SH")
			(pinfunction "SH")
			(pintype "passive")
		)
		(pad "SH" thru_hole rect
			(at 7.125 -4.1 90)
			(size 2 2)
			(drill 1.1)
			(layers "*.Cu" "*.Mask")
			(remove_unused_layers no)
			(net 379 "/SFP/SH")
			(pinfunction "SH")
			(pintype "passive")
			(solder_mask_margin 0.102)
		)
		(pad "SH" thru_hole rect
			(at 7.125 5.9 90)
			(size 2 2)
			(drill 1.1)
			(layers "*.Cu" "*.Mask")
			(remove_unused_layers no)
			(net 379 "/SFP/SH")
			(pinfunction "SH")
			(pintype "passive")
			(solder_mask_margin 0.102)
		)
		(pad "SH" thru_hole rect
			(at 7.125 15.9 90)
			(size 2 2)
			(drill 1.1)
			(layers "*.Cu" "*.Mask")
			(remove_unused_layers no)
			(net 379 "/SFP/SH")
			(pinfunction "SH")
			(pintype "passive")
			(solder_mask_margin 0.102)
		)
		(pad "SH" thru_hole rect
			(at 7.125 25.9 90)
			(size 2 2)
			(drill 1.1)
			(layers "*.Cu" "*.Mask")
			(remove_unused_layers no)
			(net 379 "/SFP/SH")
			(pinfunction "SH")
			(pintype "passive")
			(solder_mask_margin 0.102)
		)
		(zone
			(net 0)
			(net_name "")
			(layer "F.Cu")
			(hatch full 0.508)
			(connect_pads
				(clearance 0)
			)
			(min_thickness 0.01)
			(filled_areas_thickness no)
			(keepout
				(tracks allowed)
				(vias allowed)
				(pads allowed)
				(copperpour not_allowed)
				(footprints not_allowed)
			)
			(placement
				(enabled no)
				(sheetname "")
			)
			(fill
				(thermal_gap 0.508)
				(thermal_bridge_width 0.508)
			)
			(polygon
				(pts
					(xy 194.927 146.647) (xy 194.927 143.547) (xy 195.927 143.547) (xy 195.927 146.647)
				)
			)
		)
		(zone
			(net 0)
			(net_name "")
			(layer "F.Cu")
			(hatch full 0.508)
			(connect_pads
				(clearance 0)
			)
			(min_thickness 0.01)
			(filled_areas_thickness no)
			(keepout
				(tracks allowed)
				(vias allowed)
				(pads allowed)
				(copperpour not_allowed)
				(footprints not_allowed)
			)
			(placement
				(enabled no)
				(sheetname "")
			)
			(fill
				(thermal_gap 0.508)
				(thermal_bridge_width 0.508)
			)
			(polygon
				(pts
					(xy 206.727 136.777) (xy 198.727 136.777) (xy 198.727 138.777) (xy 206.727 138.777)
				)
			)
		)
		(zone
			(net 0)
			(net_name "")
			(layer "F.Cu")
			(hatch full 0.508)
			(connect_pads
				(clearance 0)
			)
			(min_thickness 0.01)
			(filled_areas_thickness no)
			(keepout
				(tracks allowed)
				(vias allowed)
				(pads allowed)
				(copperpour not_allowed)
				(footprints not_allowed)
			)
			(placement
				(enabled no)
				(sheetname "")
			)
			(fill
				(thermal_gap 0.508)
				(thermal_bridge_width 0.508)
			)
			(polygon
				(pts
					(xy 196.727 136.777) (xy 194.927 136.777) (xy 194.927 141.847) (xy 195.927 141.847) (xy 195.927 138.777)
					(xy 196.727 138.777)
				)
			)
		)
		(zone
			(net 0)
			(net_name "")
			(layer "F.Cu")
			(hatch full 0.508)
			(connect_pads
				(clearance 0)
			)
			(min_thickness 0.01)
			(filled_areas_thickness no)
			(keepout
				(tracks allowed)
				(vias allowed)
				(pads allowed)
				(copperpour not_allowed)
				(footprints not_allowed)
			)
			(placement
				(enabled no)
				(sheetname "")
			)
			(fill
				(thermal_gap 0.508)
				(thermal_bridge_width 0.508)
			)
			(polygon
				(pts
					(xy 201.727 153.027) (xy 194.927 153.027) (xy 194.927 148.347) (xy 195.927 148.347) (xy 195.927 151.027)
					(xy 201.727 151.027)
				)
			)
		)
		(zone
			(net 0)
			(net_name "")
			(layer "F.Cu")
			(hatch full 0.508)
			(connect_pads
				(clearance 0)
			)
			(min_thickness 0.01)
			(filled_areas_thickness no)
			(keepout
				(tracks allowed)
				(vias allowed)
				(pads allowed)
				(copperpour not_allowed)
				(footprints not_allowed)
			)
			(placement
				(enabled no)
				(sheetname "")
			)
			(fill
				(thermal_gap 0.508)
				(thermal_bridge_width 0.508)
			)
			(polygon
				(pts
					(xy 237.227 136.777) (xy 237.227 153.027) (xy 233.727 153.027) (xy 233.727 151.027) (xy 231.727 151.027)
					(xy 231.727 153.027) (xy 223.727 153.027) (xy 223.727 151.027) (xy 221.727 151.027) (xy 221.727 153.027)
					(xy 213.727 153.027) (xy 213.727 151.027) (xy 211.727 151.027) (xy 211.727 153.027) (xy 203.727 153.027)
					(xy 203.727 151.027) (xy 210.427 151.027) (xy 210.427 138.777) (xy 208.727 138.777) (xy 208.727 136.777)
					(xy 216.727 136.777) (xy 216.727 138.777) (xy 218.727 138.777) (xy 218.727 136.777) (xy 226.727 136.777)
					(xy 226.727 138.777) (xy 228.727 138.777) (xy 228.727 136.777)
				)
			)
		)
	)
	(footprint "antmicro-footprints:R_0402_1005Metric"
		(layer "F.Cu")
		(at 132.465349 60.98)
		(descr "Resistor SMD 0402")
		(tags "resistor SMD 0402")
		(property "Reference" "R310"
			(at 0.844651 1.38 0)
			(layer "F.SilkS")
			(effects
				(font
					(size 0.7 0.7)
					(thickness 0.15)
				)
				(justify left bottom)
			)
		)
		(property "Value" "R_200k_0402"
			(at -1.011843 1.772046 0)
			(layer "F.Fab")
			(effects
				(font
					(size 0.7 0.7)
					(thickness 0.15)
				)
				(justify left bottom)
			)
		)
		(property "Datasheet" "https://www.bourns.com/docs/product-datasheets/cr.pdf"
			(at 0 0 0)
			(layer "F.Fab")
			(hide yes)
			(effects
				(font
					(size 1.27 1.27)
					(thickness 0.15)
				)
			)
		)
		(property "Description" "SMD Chip Resistor, 200 kohm, ± 1%, 62.5 mW, 0402 [1005 Metric], Thick Film, General Purpose"
			(at 0 0 0)
			(layer "F.Fab")
			(hide yes)
			(effects
				(font
					(size 1.27 1.27)
					(thickness 0.15)
				)
			)
		)
		(property "MPN" "CR0402-FX-2003GLF"
			(at 0 0 0)
			(unlocked yes)
			(layer "F.Fab")
			(hide yes)
			(effects
				(font
					(size 1 1)
					(thickness 0.15)
				)
			)
		)
		(property "Manufacturer" "Bourns"
			(at 0 0 0)
			(unlocked yes)
			(layer "F.Fab")
			(hide yes)
			(effects
				(font
					(size 1 1)
					(thickness 0.15)
				)
			)
		)
		(property "License" "Apache-2.0"
			(at 0 0 0)
			(unlocked yes)
			(layer "F.Fab")
			(hide yes)
			(effects
				(font
					(size 1 1)
					(thickness 0.15)
				)
			)
		)
		(property "Author" "Antmicro"
			(at 0 0 0)
			(unlocked yes)
			(layer "F.Fab")
			(hide yes)
			(effects
				(font
					(size 1 1)
					(thickness 0.15)
				)
			)
		)
		(property "Val" "200k"
			(at 0 0 0)
			(unlocked yes)
			(layer "F.Fab")
			(hide yes)
			(effects
				(font
					(size 1 1)
					(thickness 0.15)
				)
			)
		)
		(property "Tolerance" "1%"
			(at 0 0 0)
			(unlocked yes)
			(layer "F.Fab")
			(hide yes)
			(effects
				(font
					(size 1 1)
					(thickness 0.15)
				)
			)
		)
		(sheetname "/DCDC/")
		(sheetfile "dcdc.kicad_sch")
		(attr smd)
		(fp_poly
			(pts
				(xy -0.925 -0.47) (xy -0.925 0.47) (xy 0.925 0.47) (xy 0.925 -0.47)
			)
			(stroke
				(width 0.05)
				(type default)
			)
			(fill no)
			(layer "F.CrtYd")
		)
		(fp_poly
			(pts
				(xy -0.5 -0.25) (xy -0.5 0.25) (xy 0.5 0.25) (xy 0.5 -0.25)
			)
			(stroke
				(width 0.15)
				(type solid)
			)
			(fill no)
			(layer "F.Fab")
		)
		(fp_text user "${REFERENCE}"
			(at -0.95 3.168 0)
			(layer "F.Fab")
			(effects
				(font
					(size 0.7 0.7)
					(thickness 0.15)
				)
				(justify left bottom)
			)
		)
		(fp_text user "Author: Antmicro"
			(at -0.95 4.169 0)
			(layer "F.Fab")
			(effects
				(font
					(size 0.7 0.7)
					(thickness 0.15)
				)
				(justify left bottom)
			)
		)
		(fp_text user "License: Apache-2.0"
			(at -0.949999 5.169 0)
			(layer "F.Fab")
			(effects
				(font
					(size 0.7 0.7)
					(thickness 0.15)
				)
				(justify left bottom)
			)
		)
		(pad "1" smd roundrect
			(at -0.48 0)
			(size 0.59 0.64)
			(layers "F.Cu" "F.Mask" "F.Paste")
			(roundrect_rratio 0.25)
			(net 1 "GND")
			(pintype "passive")
		)
		(pad "2" smd roundrect
			(at 0.48 0)
			(size 0.59 0.64)
			(layers "F.Cu" "F.Mask" "F.Paste")
			(roundrect_rratio 0.25)
			(net 1306 "/DCDC/5V_{AON}_MODE1")
			(pintype "passive")
		)
	)
	(footprint "antmicro-footprints:C_0603_1608Metric_EIA"
		(layer "F.Cu")
		(at 174.95 113.59 -90)
		(descr "Capacitor SMD 0603, IPC-7351 Density Level A")
		(tags "Capacitor 0603")
		(property "Reference" "C72"
			(at -1.18 7.369468 90)
			(layer "F.SilkS")
			(effects
				(font
					(size 0.7 0.7)
					(thickness 0.15)
				)
				(justify right top)
			)
		)
		(property "Value" "C_22u_16V_0603"
			(at -1.42757 1.770288 90)
			(layer "F.Fab")
			(effects
				(font
					(size 0.7 0.7)
					(thickness 0.15)
				)
				(justify right top)
			)
		)
		(property "Datasheet" "https://product.samsungsem.com/mlcc/CL10A226MO7JZN.do"
			(at 0 0 90)
			(layer "F.Fab")
			(hide yes)
			(effects
				(font
					(size 1.27 1.27)
					(thickness 0.15)
				)
			)
		)
		(property "Description" "SMD Multilayer Ceramic Capacitor"
			(at 0 0 90)
			(layer "F.Fab")
			(hide yes)
			(effects
				(font
					(size 1.27 1.27)
					(thickness 0.15)
				)
			)
		)
		(property "Manufacturer" "Samsung Electro-Mechanics"
			(at 0 0 270)
			(unlocked yes)
			(layer "F.Fab")
			(hide yes)
			(effects
				(font
					(size 1 1)
					(thickness 0.15)
				)
			)
		)
		(property "MPN" "CL10A226MO7JZNC"
			(at 0 0 270)
			(unlocked yes)
			(layer "F.Fab")
			(hide yes)
			(effects
				(font
					(size 1 1)
					(thickness 0.15)
				)
			)
		)
		(property "Val" "22u"
			(at 0 0 270)
			(unlocked yes)
			(layer "F.Fab")
			(hide yes)
			(effects
				(font
					(size 1 1)
					(thickness 0.15)
				)
			)
		)
		(property "License" "Apache-2.0"
			(at 0 0 270)
			(unlocked yes)
			(layer "F.Fab")
			(hide yes)
			(effects
				(font
					(size 1 1)
					(thickness 0.15)
				)
			)
		)
		(property "Author" "Antmicro"
			(at 0 0 270)
			(unlocked yes)
			(layer "F.Fab")
			(hide yes)
			(effects
				(font
					(size 1 1)
					(thickness 0.15)
				)
			)
		)
		(property "Voltage" "16V"
			(at 0 0 270)
			(unlocked yes)
			(layer "F.Fab")
			(hide yes)
			(effects
				(font
					(size 1 1)
					(thickness 0.15)
				)
			)
		)
		(property "Dielectric" ""
			(at 0 0 270)
			(unlocked yes)
			(layer "F.Fab")
			(hide yes)
			(effects
				(font
					(size 1 1)
					(thickness 0.15)
				)
			)
		)
		(sheetname "/DCDC/")
		(sheetfile "dcdc.kicad_sch")
		(attr smd)
		(fp_line
			(start -0.15 0.55)
			(end 0.15 0.55)
			(stroke
				(width 0.15)
				(type solid)
			)
			(layer "F.SilkS")
		)
		(fp_line
			(start -0.15 -0.55)
			(end 0.15 -0.55)
			(stroke
				(width 0.15)
				(type solid)
			)
			(layer "F.SilkS")
		)
		(fp_rect
			(start -1.25 -0.65)
			(end 1.25 0.65)
			(stroke
				(width 0.05)
				(type solid)
			)
			(fill no)
			(layer "F.CrtYd")
		)
		(fp_rect
			(start -0.8 -0.45)
			(end 0.8 0.45)
			(stroke
				(width 0.15)
				(type solid)
			)
			(fill no)
			(layer "F.Fab")
		)
		(fp_text user "License: Apache-2.0"
			(at -1.682 5.895 90)
			(layer "F.Fab")
			(effects
				(font
					(size 0.7 0.7)
					(thickness 0.15)
				)
				(justify right top)
			)
		)
		(fp_text user "${REFERENCE}"
			(at -1.682 3.895 90)
			(layer "F.Fab")
			(effects
				(font
					(size 0.7 0.7)
					(thickness 0.15)
				)
				(justify right top)
			)
		)
		(fp_text user "Author: Antmicro"
			(at -1.682 4.894 90)
			(layer "F.Fab")
			(effects
				(font
					(size 0.7 0.7)
					(thickness 0.15)
				)
				(justify right top)
			)
		)
		(pad "1" smd roundrect
			(at -0.7 0 270)
			(size 0.8 1.1)
			(layers "F.Cu" "F.Mask" "F.Paste")
			(roundrect_rratio 0.2)
			(net 1 "GND")
			(pintype "passive")
		)
		(pad "2" smd roundrect
			(at 0.7 0 270)
			(size 0.8 1.1)
			(layers "F.Cu" "F.Mask" "F.Paste")
			(roundrect_rratio 0.2)
			(net 253 "/DCDC/5V_OUT")
			(pintype "passive")
		)
	)
)
